(kicad_pcb
	(version 20260206)
	(generator "pcbnew")
	(generator_version "10.0")
	(general
		(thickness 1.6)
		(legacy_teardrops no)
	)
	(paper "A4")
	(title_block
		(title "03242023_DA0F0TMBIJ0_F0T_Motherboard_J_brd_V01_OCP.brd")
		(comment 1 "Grand Teton / footprints 5267-5274 of 6105")
	)
	(layers
		(0 "F.Cu" signal "TOP")
		(4 "In1.Cu" signal "GND")
		(6 "In2.Cu" signal "IN1")
		(8 "In3.Cu" signal "GND1")
		(10 "In4.Cu" signal "IN2")
		(12 "In5.Cu" signal "GND2")
		(14 "In6.Cu" signal "IN3")
		(16 "In7.Cu" signal "GND3")
		(18 "In8.Cu" signal "VCC")
		(20 "In9.Cu" signal "VCC1")
		(22 "In10.Cu" signal "GND4")
		(24 "In11.Cu" signal "IN4")
		(26 "In12.Cu" signal "GND5")
		(28 "In13.Cu" signal "IN5")
		(30 "In14.Cu" signal "GND6")
		(32 "In15.Cu" signal "IN6")
		(34 "In16.Cu" signal "GND7")
		(2 "B.Cu" signal "BOTTOM")
		(9 "F.Adhes" user "F.Adhesive")
		(11 "B.Adhes" user "B.Adhesive")
		(13 "F.Paste" user "Package Geometry/Pastemask Top")
		(15 "B.Paste" user "Package Geometry/Pastemask Bottom")
		(5 "F.SilkS" user "Ref Des/Silkscreen Top")
		(7 "B.SilkS" user "Ref Des/Silkscreen Bottom")
		(1 "F.Mask" user "Board Geometry/Soldermask Top")
		(3 "B.Mask" user "Board Geometry/Soldermask Bottom")
		(17 "Dwgs.User" user "User.Drawings")
		(19 "Cmts.User" user "User.Comments")
		(21 "Eco1.User" user "User.Eco1")
		(23 "Eco2.User" user "User.Eco2")
		(25 "Edge.Cuts" user "Board Geometry/Outline")
		(27 "Margin" user)
		(31 "F.CrtYd" user "Package Geometry/Place Bound Top")
		(29 "B.CrtYd" user "Package Geometry/Place Bound Bottom")
		(35 "F.Fab" user "Ref Des/Assembly Top")
		(33 "B.Fab" user "Ref Des/Assembly Bottom")
	)
	(footprint ""
		(layer "B.Cu")
		(at 362.674662 -210.19389 180)
		(property "Reference" "C511"
			(at 0 0 0)
			(layer "B.SilkS")
			(hide yes)
			(effects
				(font
					(size 1.27 1.27)
				)
				(justify mirror)
			)
		)
		(property "Value" ""
			(at 0 0 0)
			(layer "B.Fab")
			(effects
				(font
					(size 1.27 1.27)
				)
				(justify mirror)
			)
		)
		(duplicate_pad_numbers_are_jumpers no)
		(fp_line
			(start 1.524 0.762)
			(end 1.524 -0.762)
			(stroke
				(width 0.1524)
				(type default)
			)
			(layer "B.SilkS")
		)
		(fp_line
			(start 1.524 -0.762)
			(end -1.524 -0.762)
			(stroke
				(width 0.1524)
				(type default)
			)
			(layer "B.SilkS")
		)
		(fp_line
			(start -1.524 0.762)
			(end 1.524 0.762)
			(stroke
				(width 0.1524)
				(type default)
			)
			(layer "B.SilkS")
		)
		(fp_line
			(start -1.524 -0.762)
			(end -1.524 0.762)
			(stroke
				(width 0.1524)
				(type default)
			)
			(layer "B.SilkS")
		)
		(fp_line
			(start 1.1049 0.724916)
			(end -1.1049 0.724916)
			(stroke
				(width 0.1)
				(type default)
			)
			(layer "B.Fab")
		)
		(fp_line
			(start 1.1049 -0.724916)
			(end 1.1049 0.724916)
			(stroke
				(width 0.1)
				(type default)
			)
			(layer "B.Fab")
		)
		(fp_line
			(start -1.1049 0.724916)
			(end -1.1049 -0.724916)
			(stroke
				(width 0.1)
				(type default)
			)
			(layer "B.Fab")
		)
		(fp_line
			(start -1.1049 -0.724916)
			(end 1.1049 -0.724916)
			(stroke
				(width 0.1)
				(type default)
			)
			(layer "B.Fab")
		)
		(pad "1" smd rect
			(at 0.889 0 180)
			(size 1.016 1.27)
			(layers "B.Cu" "B.Mask" "B.Paste")
			(net "PVCCD_HV_CPU0")
		)
		(pad "2" smd rect
			(at -0.889 0 180)
			(size 1.016 1.27)
			(layers "B.Cu" "B.Mask" "B.Paste")
			(net "GND")
		)
	)
	(footprint ""
		(layer "B.Cu")
		(at 435.549802 -11.088116 180)
		(property "Reference" "C1239"
			(at 0 0 0)
			(layer "B.SilkS")
			(hide yes)
			(effects
				(font
					(size 1.27 1.27)
				)
				(justify mirror)
			)
		)
		(property "Value" ""
			(at 0 0 0)
			(layer "B.Fab")
			(effects
				(font
					(size 1.27 1.27)
				)
				(justify mirror)
			)
		)
		(duplicate_pad_numbers_are_jumpers no)
		(fp_line
			(start 0.7874 0.4064)
			(end 0.7874 -0.4064)
			(stroke
				(width 0.1524)
				(type default)
			)
			(layer "B.SilkS")
		)
		(fp_line
			(start 0.7874 -0.4064)
			(end -0.7874 -0.4064)
			(stroke
				(width 0.1524)
				(type default)
			)
			(layer "B.SilkS")
		)
		(fp_line
			(start -0.7874 0.4064)
			(end 0.7874 0.4064)
			(stroke
				(width 0.1524)
				(type default)
			)
			(layer "B.SilkS")
		)
		(fp_line
			(start -0.7874 -0.4064)
			(end -0.7874 0.4064)
			(stroke
				(width 0.1524)
				(type default)
			)
			(layer "B.SilkS")
		)
		(fp_line
			(start 0.67945 0.3048)
			(end 0.67945 -0.305054)
			(stroke
				(width 0.1)
				(type default)
			)
			(layer "B.Fab")
		)
		(fp_line
			(start 0.67945 -0.305054)
			(end 0.12065 -0.305054)
			(stroke
				(width 0.1)
				(type default)
			)
			(layer "B.Fab")
		)
		(fp_line
			(start 0.12065 0.3048)
			(end 0.67945 0.3048)
			(stroke
				(width 0.1)
				(type default)
			)
			(layer "B.Fab")
		)
		(fp_line
			(start 0.12065 0.2794)
			(end 0.12065 0.3048)
			(stroke
				(width 0.1)
				(type default)
			)
			(layer "B.Fab")
		)
		(fp_line
			(start 0.12065 -0.2794)
			(end -0.12065 -0.2794)
			(stroke
				(width 0.1)
				(type default)
			)
			(layer "B.Fab")
		)
		(fp_line
			(start 0.12065 -0.305054)
			(end 0.12065 -0.2794)
			(stroke
				(width 0.1)
				(type default)
			)
			(layer "B.Fab")
		)
		(fp_line
			(start -0.120396 0.3048)
			(end -0.120396 0.2794)
			(stroke
				(width 0.1)
				(type default)
			)
			(layer "B.Fab")
		)
		(fp_line
			(start -0.120396 0.2794)
			(end 0.12065 0.2794)
			(stroke
				(width 0.1)
				(type default)
			)
			(layer "B.Fab")
		)
		(fp_line
			(start -0.12065 -0.2794)
			(end -0.12065 -0.3048)
			(stroke
				(width 0.1)
				(type default)
			)
			(layer "B.Fab")
		)
		(fp_line
			(start -0.12065 -0.3048)
			(end -0.67945 -0.3048)
			(stroke
				(width 0.1)
				(type default)
			)
			(layer "B.Fab")
		)
		(fp_line
			(start -0.67945 0.3048)
			(end -0.120396 0.3048)
			(stroke
				(width 0.1)
				(type default)
			)
			(layer "B.Fab")
		)
		(fp_line
			(start -0.67945 -0.3048)
			(end -0.67945 0.3048)
			(stroke
				(width 0.1)
				(type default)
			)
			(layer "B.Fab")
		)
		(pad "1" smd circle
			(at 0.40005 0)
			(size 0 0)
			(layers "B.Cu" "B.Mask" "B.Paste")
			(net "P3V3_OCP_SFF")
		)
		(pad "2" smd circle
			(at -0.40005 0)
			(size 0 0)
			(layers "B.Cu" "B.Mask" "B.Paste")
			(net "GND")
		)
	)
	(footprint ""
		(layer "B.Cu")
		(at 312.93054 -48.890428 180)
		(property "Reference" "R1944"
			(at 0 0 0)
			(layer "B.SilkS")
			(hide yes)
			(effects
				(font
					(size 1.27 1.27)
				)
				(justify mirror)
			)
		)
		(property "Value" ""
			(at 0 0 0)
			(layer "B.Fab")
			(effects
				(font
					(size 1.27 1.27)
				)
				(justify mirror)
			)
		)
		(duplicate_pad_numbers_are_jumpers no)
		(fp_line
			(start 0.7874 0.4064)
			(end 0.7874 -0.4064)
			(stroke
				(width 0.1524)
				(type default)
			)
			(layer "B.SilkS")
		)
		(fp_line
			(start 0.7874 -0.4064)
			(end -0.7874 -0.4064)
			(stroke
				(width 0.1524)
				(type default)
			)
			(layer "B.SilkS")
		)
		(fp_line
			(start -0.7874 0.4064)
			(end 0.7874 0.4064)
			(stroke
				(width 0.1524)
				(type default)
			)
			(layer "B.SilkS")
		)
		(fp_line
			(start -0.7874 -0.4064)
			(end -0.7874 0.4064)
			(stroke
				(width 0.1524)
				(type default)
			)
			(layer "B.SilkS")
		)
		(fp_line
			(start 0.67945 0.3048)
			(end 0.67945 -0.305054)
			(stroke
				(width 0.1)
				(type default)
			)
			(layer "B.Fab")
		)
		(fp_line
			(start 0.67945 -0.305054)
			(end 0.12065 -0.305054)
			(stroke
				(width 0.1)
				(type default)
			)
			(layer "B.Fab")
		)
		(fp_line
			(start 0.12065 0.3048)
			(end 0.67945 0.3048)
			(stroke
				(width 0.1)
				(type default)
			)
			(layer "B.Fab")
		)
		(fp_line
			(start 0.12065 0.2794)
			(end 0.12065 0.3048)
			(stroke
				(width 0.1)
				(type default)
			)
			(layer "B.Fab")
		)
		(fp_line
			(start 0.12065 -0.2794)
			(end -0.12065 -0.2794)
			(stroke
				(width 0.1)
				(type default)
			)
			(layer "B.Fab")
		)
		(fp_line
			(start 0.12065 -0.305054)
			(end 0.12065 -0.2794)
			(stroke
				(width 0.1)
				(type default)
			)
			(layer "B.Fab")
		)
		(fp_line
			(start -0.120396 0.3048)
			(end -0.120396 0.2794)
			(stroke
				(width 0.1)
				(type default)
			)
			(layer "B.Fab")
		)
		(fp_line
			(start -0.120396 0.2794)
			(end 0.12065 0.2794)
			(stroke
				(width 0.1)
				(type default)
			)
			(layer "B.Fab")
		)
		(fp_line
			(start -0.12065 -0.2794)
			(end -0.12065 -0.3048)
			(stroke
				(width 0.1)
				(type default)
			)
			(layer "B.Fab")
		)
		(fp_line
			(start -0.12065 -0.3048)
			(end -0.67945 -0.3048)
			(stroke
				(width 0.1)
				(type default)
			)
			(layer "B.Fab")
		)
		(fp_line
			(start -0.67945 0.3048)
			(end -0.120396 0.3048)
			(stroke
				(width 0.1)
				(type default)
			)
			(layer "B.Fab")
		)
		(fp_line
			(start -0.67945 -0.3048)
			(end -0.67945 0.3048)
			(stroke
				(width 0.1)
				(type default)
			)
			(layer "B.Fab")
		)
		(pad "1" smd circle
			(at 0.40005 0)
			(size 0 0)
			(layers "B.Cu" "B.Mask" "B.Paste")
			(net "IRQ_PCH_SCI_WHEA_R_N")
		)
		(pad "2" smd circle
			(at -0.40005 0)
			(size 0 0)
			(layers "B.Cu" "B.Mask" "B.Paste")
			(net "IRQ_PCH_SCI_WHEA_N")
		)
	)
	(footprint ""
		(layer "B.Cu")
		(at 136.417558 -333.62138 -90)
		(property "Reference" "PC497_P1_8"
			(at 0 0 90)
			(layer "B.SilkS")
			(hide yes)
			(effects
				(font
					(size 1.27 1.27)
				)
				(justify mirror)
			)
		)
		(property "Value" ""
			(at 0 0 90)
			(layer "B.Fab")
			(effects
				(font
					(size 1.27 1.27)
				)
				(justify mirror)
			)
		)
		(duplicate_pad_numbers_are_jumpers no)
		(fp_line
			(start -1.524 0.762)
			(end 1.524 0.762)
			(stroke
				(width 0.1524)
				(type default)
			)
			(layer "B.SilkS")
		)
		(fp_line
			(start 1.524 0.762)
			(end 1.524 -0.762)
			(stroke
				(width 0.1524)
				(type default)
			)
			(layer "B.SilkS")
		)
		(fp_line
			(start -1.524 -0.762)
			(end -1.524 0.762)
			(stroke
				(width 0.1524)
				(type default)
			)
			(layer "B.SilkS")
		)
		(fp_line
			(start 1.524 -0.762)
			(end -1.524 -0.762)
			(stroke
				(width 0.1524)
				(type default)
			)
			(layer "B.SilkS")
		)
		(fp_line
			(start -1.1049 0.724916)
			(end -1.1049 -0.724916)
			(stroke
				(width 0.1)
				(type default)
			)
			(layer "B.Fab")
		)
		(fp_line
			(start 1.1049 0.724916)
			(end -1.1049 0.724916)
			(stroke
				(width 0.1)
				(type default)
			)
			(layer "B.Fab")
		)
		(fp_line
			(start -1.1049 -0.724916)
			(end 1.1049 -0.724916)
			(stroke
				(width 0.1)
				(type default)
			)
			(layer "B.Fab")
		)
		(fp_line
			(start 1.1049 -0.724916)
			(end 1.1049 0.724916)
			(stroke
				(width 0.1)
				(type default)
			)
			(layer "B.Fab")
		)
		(pad "1" smd rect
			(at 0.889 0 270)
			(size 1.016 1.27)
			(layers "B.Cu" "B.Mask" "B.Paste")
			(net "PVCCIN_CPU1")
		)
		(pad "2" smd rect
			(at -0.889 0 270)
			(size 1.016 1.27)
			(layers "B.Cu" "B.Mask" "B.Paste")
			(net "GND")
		)
	)
	(footprint ""
		(layer "B.Cu")
		(at 237.836202 -127.48895 180)
		(property "Reference" "C210"
			(at 0 0 0)
			(layer "B.SilkS")
			(hide yes)
			(effects
				(font
					(size 1.27 1.27)
				)
				(justify mirror)
			)
		)
		(property "Value" ""
			(at 0 0 0)
			(layer "B.Fab")
			(effects
				(font
					(size 1.27 1.27)
				)
				(justify mirror)
			)
		)
		(duplicate_pad_numbers_are_jumpers no)
		(fp_line
			(start 0.7874 0.4064)
			(end 0.7874 -0.4064)
			(stroke
				(width 0.1524)
				(type default)
			)
			(layer "B.SilkS")
		)
		(fp_line
			(start 0.7874 -0.4064)
			(end -0.7874 -0.4064)
			(stroke
				(width 0.1524)
				(type default)
			)
			(layer "B.SilkS")
		)
		(fp_line
			(start -0.7874 0.4064)
			(end 0.7874 0.4064)
			(stroke
				(width 0.1524)
				(type default)
			)
			(layer "B.SilkS")
		)
		(fp_line
			(start -0.7874 -0.4064)
			(end -0.7874 0.4064)
			(stroke
				(width 0.1524)
				(type default)
			)
			(layer "B.SilkS")
		)
		(fp_line
			(start 0.67945 0.3048)
			(end 0.67945 -0.305054)
			(stroke
				(width 0.1)
				(type default)
			)
			(layer "B.Fab")
		)
		(fp_line
			(start 0.67945 -0.305054)
			(end 0.12065 -0.305054)
			(stroke
				(width 0.1)
				(type default)
			)
			(layer "B.Fab")
		)
		(fp_line
			(start 0.12065 0.3048)
			(end 0.67945 0.3048)
			(stroke
				(width 0.1)
				(type default)
			)
			(layer "B.Fab")
		)
		(fp_line
			(start 0.12065 0.2794)
			(end 0.12065 0.3048)
			(stroke
				(width 0.1)
				(type default)
			)
			(layer "B.Fab")
		)
		(fp_line
			(start 0.12065 -0.2794)
			(end -0.12065 -0.2794)
			(stroke
				(width 0.1)
				(type default)
			)
			(layer "B.Fab")
		)
		(fp_line
			(start 0.12065 -0.305054)
			(end 0.12065 -0.2794)
			(stroke
				(width 0.1)
				(type default)
			)
			(layer "B.Fab")
		)
		(fp_line
			(start -0.120396 0.3048)
			(end -0.120396 0.2794)
			(stroke
				(width 0.1)
				(type default)
			)
			(layer "B.Fab")
		)
		(fp_line
			(start -0.120396 0.2794)
			(end 0.12065 0.2794)
			(stroke
				(width 0.1)
				(type default)
			)
			(layer "B.Fab")
		)
		(fp_line
			(start -0.12065 -0.2794)
			(end -0.12065 -0.3048)
			(stroke
				(width 0.1)
				(type default)
			)
			(layer "B.Fab")
		)
		(fp_line
			(start -0.12065 -0.3048)
			(end -0.67945 -0.3048)
			(stroke
				(width 0.1)
				(type default)
			)
			(layer "B.Fab")
		)
		(fp_line
			(start -0.67945 0.3048)
			(end -0.120396 0.3048)
			(stroke
				(width 0.1)
				(type default)
			)
			(layer "B.Fab")
		)
		(fp_line
			(start -0.67945 -0.3048)
			(end -0.67945 0.3048)
			(stroke
				(width 0.1)
				(type default)
			)
			(layer "B.Fab")
		)
		(pad "1" smd circle
			(at 0.40005 0)
			(size 0 0)
			(layers "B.Cu" "B.Mask" "B.Paste")
			(net "P3V3_DB2000_VDDR")
		)
		(pad "2" smd circle
			(at -0.40005 0)
			(size 0 0)
			(layers "B.Cu" "B.Mask" "B.Paste")
			(net "GND")
		)
	)
	(footprint ""
		(layer "B.Cu")
		(at 53.446426 -316.213744)
		(property "Reference" "R3891"
			(at 0 0 0)
			(layer "B.SilkS")
			(hide yes)
			(effects
				(font
					(size 1.27 1.27)
				)
				(justify mirror)
			)
		)
		(property "Value" ""
			(at 0 0 0)
			(layer "B.Fab")
			(effects
				(font
					(size 1.27 1.27)
				)
				(justify mirror)
			)
		)
		(duplicate_pad_numbers_are_jumpers no)
		(fp_line
			(start -0.7874 -0.4064)
			(end -0.7874 0.4064)
			(stroke
				(width 0.1524)
				(type default)
			)
			(layer "B.SilkS")
		)
		(fp_line
			(start -0.7874 0.4064)
			(end 0.7874 0.4064)
			(stroke
				(width 0.1524)
				(type default)
			)
			(layer "B.SilkS")
		)
		(fp_line
			(start 0.7874 -0.4064)
			(end -0.7874 -0.4064)
			(stroke
				(width 0.1524)
				(type default)
			)
			(layer "B.SilkS")
		)
		(fp_line
			(start 0.7874 0.4064)
			(end 0.7874 -0.4064)
			(stroke
				(width 0.1524)
				(type default)
			)
			(layer "B.SilkS")
		)
		(fp_line
			(start -0.67945 -0.3048)
			(end -0.67945 0.3048)
			(stroke
				(width 0.1)
				(type default)
			)
			(layer "B.Fab")
		)
		(fp_line
			(start -0.67945 0.3048)
			(end -0.120396 0.3048)
			(stroke
				(width 0.1)
				(type default)
			)
			(layer "B.Fab")
		)
		(fp_line
			(start -0.12065 -0.3048)
			(end -0.67945 -0.3048)
			(stroke
				(width 0.1)
				(type default)
			)
			(layer "B.Fab")
		)
		(fp_line
			(start -0.12065 -0.2794)
			(end -0.12065 -0.3048)
			(stroke
				(width 0.1)
				(type default)
			)
			(layer "B.Fab")
		)
		(fp_line
			(start -0.120396 0.2794)
			(end 0.12065 0.2794)
			(stroke
				(width 0.1)
				(type default)
			)
			(layer "B.Fab")
		)
		(fp_line
			(start -0.120396 0.3048)
			(end -0.120396 0.2794)
			(stroke
				(width 0.1)
				(type default)
			)
			(layer "B.Fab")
		)
		(fp_line
			(start 0.12065 -0.305054)
			(end 0.12065 -0.2794)
			(stroke
				(width 0.1)
				(type default)
			)
			(layer "B.Fab")
		)
		(fp_line
			(start 0.12065 -0.2794)
			(end -0.12065 -0.2794)
			(stroke
				(width 0.1)
				(type default)
			)
			(layer "B.Fab")
		)
		(fp_line
			(start 0.12065 0.2794)
			(end 0.12065 0.3048)
			(stroke
				(width 0.1)
				(type default)
			)
			(layer "B.Fab")
		)
		(fp_line
			(start 0.12065 0.3048)
			(end 0.67945 0.3048)
			(stroke
				(width 0.1)
				(type default)
			)
			(layer "B.Fab")
		)
		(fp_line
			(start 0.67945 -0.305054)
			(end 0.12065 -0.305054)
			(stroke
				(width 0.1)
				(type default)
			)
			(layer "B.Fab")
		)
		(fp_line
			(start 0.67945 0.3048)
			(end 0.67945 -0.305054)
			(stroke
				(width 0.1)
				(type default)
			)
			(layer "B.Fab")
		)
		(pad "1" smd circle
			(at 0.40005 0 180)
			(size 0 0)
			(layers "B.Cu" "B.Mask" "B.Paste")
			(net "I3C_SPD_DDRABCD_CPU1_LVC1_SCL_R")
		)
		(pad "2" smd circle
			(at -0.40005 0 180)
			(size 0 0)
			(layers "B.Cu" "B.Mask" "B.Paste")
			(net "I3C_SPD_DDRABCD_CPU1_LVC1_SCL")
		)
	)
	(footprint ""
		(layer "B.Cu")
		(at 125.052836 -24.986742 180)
		(property "Reference" "C1096"
			(at 0 0 0)
			(layer "B.SilkS")
			(hide yes)
			(effects
				(font
					(size 1.27 1.27)
				)
				(justify mirror)
			)
		)
		(property "Value" ""
			(at 0 0 0)
			(layer "B.Fab")
			(effects
				(font
					(size 1.27 1.27)
				)
				(justify mirror)
			)
		)
		(duplicate_pad_numbers_are_jumpers no)
		(fp_line
			(start 0.299974 0.150114)
			(end 0.299974 -0.150114)
			(stroke
				(width 0.1)
				(type default)
			)
			(layer "B.Fab")
		)
		(fp_line
			(start 0.299974 -0.150114)
			(end -0.299974 -0.150114)
			(stroke
				(width 0.1)
				(type default)
			)
			(layer "B.Fab")
		)
		(fp_line
			(start -0.299974 0.150114)
			(end 0.299974 0.150114)
			(stroke
				(width 0.1)
				(type default)
			)
			(layer "B.Fab")
		)
		(fp_line
			(start -0.299974 -0.150114)
			(end -0.299974 0.150114)
			(stroke
				(width 0.1)
				(type default)
			)
			(layer "B.Fab")
		)
		(pad "1" smd rect
			(at 0.2667 0)
			(size 0.3048 0.381)
			(layers "B.Cu" "B.Mask" "B.Paste")
			(net "USB3_PCH_TX_DP<4>")
		)
		(pad "2" smd rect
			(at -0.2667 0)
			(size 0.3048 0.381)
			(layers "B.Cu" "B.Mask" "B.Paste")
			(net "USB3_PCH_TX_C_DP<4>")
		)
	)
	(footprint ""
		(layer "B.Cu")
		(at 272.363946 -71.341996)
		(property "Reference" "PC1225"
			(at 0 0 0)
			(layer "B.SilkS")
			(hide yes)
			(effects
				(font
					(size 1.27 1.27)
				)
				(justify mirror)
			)
		)
		(property "Value" ""
			(at 0 0 0)
			(layer "B.Fab")
			(effects
				(font
					(size 1.27 1.27)
				)
				(justify mirror)
			)
		)
		(duplicate_pad_numbers_are_jumpers no)
		(fp_line
			(start -1.524 -0.762)
			(end -1.524 0.762)
			(stroke
				(width 0.1524)
				(type default)
			)
			(layer "B.SilkS")
		)
		(fp_line
			(start -1.524 0.762)
			(end 1.524 0.762)
			(stroke
				(width 0.1524)
				(type default)
			)
			(layer "B.SilkS")
		)
		(fp_line
			(start 1.524 -0.762)
			(end -1.524 -0.762)
			(stroke
				(width 0.1524)
				(type default)
			)
			(layer "B.SilkS")
		)
		(fp_line
			(start 1.524 0.762)
			(end 1.524 -0.762)
			(stroke
				(width 0.1524)
				(type default)
			)
			(layer "B.SilkS")
		)
		(fp_line
			(start -1.1049 -0.724916)
			(end 1.1049 -0.724916)
			(stroke
				(width 0.1)
				(type default)
			)
			(layer "B.Fab")
		)
		(fp_line
			(start -1.1049 0.724916)
			(end -1.1049 -0.724916)
			(stroke
				(width 0.1)
				(type default)
			)
			(layer "B.Fab")
		)
		(fp_line
			(start 1.1049 -0.724916)
			(end 1.1049 0.724916)
			(stroke
				(width 0.1)
				(type default)
			)
			(layer "B.Fab")
		)
		(fp_line
			(start 1.1049 0.724916)
			(end -1.1049 0.724916)
			(stroke
				(width 0.1)
				(type default)
			)
			(layer "B.Fab")
		)
		(pad "1" smd rect
			(at 0.889 0)
			(size 1.016 1.27)
			(layers "B.Cu" "B.Mask" "B.Paste")
			(net "P1V05_PCH_AUX")
		)
		(pad "2" smd rect
			(at -0.889 0)
			(size 1.016 1.27)
			(layers "B.Cu" "B.Mask" "B.Paste")
			(net "GND")
		)
	)
)
